(kicad_pcb
	(version 20260206)
	(generator "pcbnew")
	(generator_version "10.0")
	(general
		(thickness 1.6)
		(legacy_teardrops no)
	)
	(paper "A4")
	(title_block
		(title "01162023_DA0F0TEBIF0_F0T_Expander_BD_F_brd_V02_OCP.brd")
		(comment 1 "Grand Teton / footprints 5077-5084 of 9728")
	)
	(layers
		(0 "F.Cu" signal "TOP")
		(4 "In1.Cu" signal "GND")
		(6 "In2.Cu" signal "VCC")
		(8 "In3.Cu" signal "VCC1")
		(10 "In4.Cu" signal "GND1")
		(12 "In5.Cu" signal "IN1")
		(14 "In6.Cu" signal "GND2")
		(16 "In7.Cu" signal "IN2")
		(18 "In8.Cu" signal "GND3")
		(20 "In9.Cu" signal "IN3")
		(22 "In10.Cu" signal "GND4")
		(24 "In11.Cu" signal "IN4")
		(26 "In12.Cu" signal "GND5")
		(28 "In13.Cu" signal "IN5")
		(30 "In14.Cu" signal "GND6")
		(32 "In15.Cu" signal "IN6")
		(34 "In16.Cu" signal "GND7")
		(2 "B.Cu" signal "BOTTOM")
		(9 "F.Adhes" user "F.Adhesive")
		(11 "B.Adhes" user "B.Adhesive")
		(13 "F.Paste" user "Package Geometry/Pastemask Top")
		(15 "B.Paste" user "Package Geometry/Pastemask Bottom")
		(5 "F.SilkS" user "Ref Des/Silkscreen Top")
		(7 "B.SilkS" user "Ref Des/Silkscreen Bottom")
		(1 "F.Mask" user "Board Geometry/Soldermask Top")
		(3 "B.Mask" user "Board Geometry/Soldermask Bottom")
		(17 "Dwgs.User" user "User.Drawings")
		(19 "Cmts.User" user "User.Comments")
		(21 "Eco1.User" user "User.Eco1")
		(23 "Eco2.User" user "User.Eco2")
		(25 "Edge.Cuts" user "Board Geometry/Outline")
		(27 "Margin" user)
		(31 "F.CrtYd" user "Package Geometry/Place Bound Top")
		(29 "B.CrtYd" user "Package Geometry/Place Bound Bottom")
		(35 "F.Fab" user "Ref Des/Assembly Top")
		(33 "B.Fab" user "Ref Des/Assembly Bottom")
	)
	(footprint ""
		(layer "F.Cu")
		(at 154.931872 -147.969224 90)
		(property "Reference" "C875"
			(at 0 0 90)
			(layer "F.SilkS")
			(hide yes)
			(effects
				(font
					(size 1.27 1.27)
				)
			)
		)
		(property "Value" ""
			(at 0 0 90)
			(layer "F.Fab")
			(effects
				(font
					(size 1.27 1.27)
				)
			)
		)
		(duplicate_pad_numbers_are_jumpers no)
		(fp_line
			(start 1.524 -0.762)
			(end 1.524 0.762)
			(stroke
				(width 0.1524)
				(type default)
			)
			(layer "F.SilkS")
		)
		(fp_line
			(start -1.524 -0.762)
			(end 1.524 -0.762)
			(stroke
				(width 0.1524)
				(type default)
			)
			(layer "F.SilkS")
		)
		(fp_line
			(start 1.524 0.762)
			(end -1.524 0.762)
			(stroke
				(width 0.1524)
				(type default)
			)
			(layer "F.SilkS")
		)
		(fp_line
			(start -1.524 0.762)
			(end -1.524 -0.762)
			(stroke
				(width 0.1524)
				(type default)
			)
			(layer "F.SilkS")
		)
		(fp_line
			(start 1.1049 -0.724916)
			(end -1.1049 -0.724916)
			(stroke
				(width 0.1)
				(type default)
			)
			(layer "F.Fab")
		)
		(fp_line
			(start -1.1049 -0.724916)
			(end -1.1049 0.724916)
			(stroke
				(width 0.1)
				(type default)
			)
			(layer "F.Fab")
		)
		(fp_line
			(start 1.1049 0.724916)
			(end 1.1049 -0.724916)
			(stroke
				(width 0.1)
				(type default)
			)
			(layer "F.Fab")
		)
		(fp_line
			(start -1.1049 0.724916)
			(end 1.1049 0.724916)
			(stroke
				(width 0.1)
				(type default)
			)
			(layer "F.Fab")
		)
		(pad "1" smd rect
			(at -0.889 0 270)
			(size 1.016 1.27)
			(layers "F.Cu" "F.Mask" "F.Paste")
			(net "P12V_NIC2")
		)
		(pad "2" smd rect
			(at 0.889 0 270)
			(size 1.016 1.27)
			(layers "F.Cu" "F.Mask" "F.Paste")
			(net "GND")
		)
	)
	(footprint ""
		(layer "F.Cu")
		(at 387.09092 -142.892018)
		(property "Reference" "R336"
			(at 0 0 0)
			(layer "F.SilkS")
			(hide yes)
			(effects
				(font
					(size 1.27 1.27)
				)
			)
		)
		(property "Value" ""
			(at 0 0 0)
			(layer "F.Fab")
			(effects
				(font
					(size 1.27 1.27)
				)
			)
		)
		(duplicate_pad_numbers_are_jumpers no)
		(fp_line
			(start -0.7874 -0.4064)
			(end 0.7874 -0.4064)
			(stroke
				(width 0.1524)
				(type default)
			)
			(layer "F.SilkS")
		)
		(fp_line
			(start -0.7874 0.4064)
			(end -0.7874 -0.4064)
			(stroke
				(width 0.1524)
				(type default)
			)
			(layer "F.SilkS")
		)
		(fp_line
			(start 0.7874 -0.4064)
			(end 0.7874 0.4064)
			(stroke
				(width 0.1524)
				(type default)
			)
			(layer "F.SilkS")
		)
		(fp_line
			(start 0.7874 0.4064)
			(end -0.7874 0.4064)
			(stroke
				(width 0.1524)
				(type default)
			)
			(layer "F.SilkS")
		)
		(fp_line
			(start -0.67945 -0.305054)
			(end -0.12065 -0.305054)
			(stroke
				(width 0.1)
				(type default)
			)
			(layer "F.Fab")
		)
		(fp_line
			(start -0.67945 0.3048)
			(end -0.67945 -0.305054)
			(stroke
				(width 0.1)
				(type default)
			)
			(layer "F.Fab")
		)
		(fp_line
			(start -0.12065 -0.305054)
			(end -0.12065 -0.2794)
			(stroke
				(width 0.1)
				(type default)
			)
			(layer "F.Fab")
		)
		(fp_line
			(start -0.12065 -0.2794)
			(end 0.12065 -0.2794)
			(stroke
				(width 0.1)
				(type default)
			)
			(layer "F.Fab")
		)
		(fp_line
			(start -0.12065 0.2794)
			(end -0.12065 0.3048)
			(stroke
				(width 0.1)
				(type default)
			)
			(layer "F.Fab")
		)
		(fp_line
			(start -0.12065 0.3048)
			(end -0.67945 0.3048)
			(stroke
				(width 0.1)
				(type default)
			)
			(layer "F.Fab")
		)
		(fp_line
			(start 0.120396 0.2794)
			(end -0.12065 0.2794)
			(stroke
				(width 0.1)
				(type default)
			)
			(layer "F.Fab")
		)
		(fp_line
			(start 0.120396 0.3048)
			(end 0.120396 0.2794)
			(stroke
				(width 0.1)
				(type default)
			)
			(layer "F.Fab")
		)
		(fp_line
			(start 0.12065 -0.3048)
			(end 0.67945 -0.3048)
			(stroke
				(width 0.1)
				(type default)
			)
			(layer "F.Fab")
		)
		(fp_line
			(start 0.12065 -0.2794)
			(end 0.12065 -0.3048)
			(stroke
				(width 0.1)
				(type default)
			)
			(layer "F.Fab")
		)
		(fp_line
			(start 0.67945 -0.3048)
			(end 0.67945 0.3048)
			(stroke
				(width 0.1)
				(type default)
			)
			(layer "F.Fab")
		)
		(fp_line
			(start 0.67945 0.3048)
			(end 0.120396 0.3048)
			(stroke
				(width 0.1)
				(type default)
			)
			(layer "F.Fab")
		)
		(pad "1" smd circle
			(at -0.40005 0)
			(size 0 0)
			(layers "F.Cu" "F.Mask" "F.Paste")
			(net "NIC6_BIF0_N")
		)
		(pad "2" smd circle
			(at 0.40005 0)
			(size 0 0)
			(layers "F.Cu" "F.Mask" "F.Paste")
			(net "GND")
		)
	)
	(footprint ""
		(layer "F.Cu")
		(at 366.169448 -254.385572)
		(property "Reference" "R3068"
			(at 0 0 0)
			(layer "F.SilkS")
			(hide yes)
			(effects
				(font
					(size 1.27 1.27)
				)
			)
		)
		(property "Value" ""
			(at 0 0 0)
			(layer "F.Fab")
			(effects
				(font
					(size 1.27 1.27)
				)
			)
		)
		(duplicate_pad_numbers_are_jumpers no)
		(fp_line
			(start -0.7874 -0.4064)
			(end 0.7874 -0.4064)
			(stroke
				(width 0.1524)
				(type default)
			)
			(layer "F.SilkS")
		)
		(fp_line
			(start -0.7874 0.4064)
			(end -0.7874 -0.4064)
			(stroke
				(width 0.1524)
				(type default)
			)
			(layer "F.SilkS")
		)
		(fp_line
			(start 0.7874 -0.4064)
			(end 0.7874 0.4064)
			(stroke
				(width 0.1524)
				(type default)
			)
			(layer "F.SilkS")
		)
		(fp_line
			(start 0.7874 0.4064)
			(end -0.7874 0.4064)
			(stroke
				(width 0.1524)
				(type default)
			)
			(layer "F.SilkS")
		)
		(fp_line
			(start -0.67945 -0.305054)
			(end -0.12065 -0.305054)
			(stroke
				(width 0.1)
				(type default)
			)
			(layer "F.Fab")
		)
		(fp_line
			(start -0.67945 0.3048)
			(end -0.67945 -0.305054)
			(stroke
				(width 0.1)
				(type default)
			)
			(layer "F.Fab")
		)
		(fp_line
			(start -0.12065 -0.305054)
			(end -0.12065 -0.2794)
			(stroke
				(width 0.1)
				(type default)
			)
			(layer "F.Fab")
		)
		(fp_line
			(start -0.12065 -0.2794)
			(end 0.12065 -0.2794)
			(stroke
				(width 0.1)
				(type default)
			)
			(layer "F.Fab")
		)
		(fp_line
			(start -0.12065 0.2794)
			(end -0.12065 0.3048)
			(stroke
				(width 0.1)
				(type default)
			)
			(layer "F.Fab")
		)
		(fp_line
			(start -0.12065 0.3048)
			(end -0.67945 0.3048)
			(stroke
				(width 0.1)
				(type default)
			)
			(layer "F.Fab")
		)
		(fp_line
			(start 0.120396 0.2794)
			(end -0.12065 0.2794)
			(stroke
				(width 0.1)
				(type default)
			)
			(layer "F.Fab")
		)
		(fp_line
			(start 0.120396 0.3048)
			(end 0.120396 0.2794)
			(stroke
				(width 0.1)
				(type default)
			)
			(layer "F.Fab")
		)
		(fp_line
			(start 0.12065 -0.3048)
			(end 0.67945 -0.3048)
			(stroke
				(width 0.1)
				(type default)
			)
			(layer "F.Fab")
		)
		(fp_line
			(start 0.12065 -0.2794)
			(end 0.12065 -0.3048)
			(stroke
				(width 0.1)
				(type default)
			)
			(layer "F.Fab")
		)
		(fp_line
			(start 0.67945 -0.3048)
			(end 0.67945 0.3048)
			(stroke
				(width 0.1)
				(type default)
			)
			(layer "F.Fab")
		)
		(fp_line
			(start 0.67945 0.3048)
			(end 0.120396 0.3048)
			(stroke
				(width 0.1)
				(type default)
			)
			(layer "F.Fab")
		)
		(pad "1" smd circle
			(at -0.40005 0)
			(size 0 0)
			(layers "F.Cu" "F.Mask" "F.Paste")
			(net "PWR_EN_PEX")
		)
		(pad "2" smd circle
			(at 0.40005 0)
			(size 0 0)
			(layers "F.Cu" "F.Mask" "F.Paste")
			(net "PWR_EN_PEX_R1")
		)
	)
	(footprint ""
		(layer "F.Cu")
		(at 315.850016 -50.96383 180)
		(property "Reference" "PC586"
			(at 0 0 180)
			(layer "F.SilkS")
			(hide yes)
			(effects
				(font
					(size 1.27 1.27)
				)
			)
		)
		(property "Value" ""
			(at 0 0 180)
			(layer "F.Fab")
			(effects
				(font
					(size 1.27 1.27)
				)
			)
		)
		(duplicate_pad_numbers_are_jumpers no)
		(fp_line
			(start 1.524 0.762)
			(end -1.524 0.762)
			(stroke
				(width 0.1524)
				(type default)
			)
			(layer "F.SilkS")
		)
		(fp_line
			(start 1.524 -0.762)
			(end 1.524 0.762)
			(stroke
				(width 0.1524)
				(type default)
			)
			(layer "F.SilkS")
		)
		(fp_line
			(start -1.524 0.762)
			(end -1.524 -0.762)
			(stroke
				(width 0.1524)
				(type default)
			)
			(layer "F.SilkS")
		)
		(fp_line
			(start -1.524 -0.762)
			(end 1.524 -0.762)
			(stroke
				(width 0.1524)
				(type default)
			)
			(layer "F.SilkS")
		)
		(fp_line
			(start 1.1049 0.724916)
			(end 1.1049 -0.724916)
			(stroke
				(width 0.1)
				(type default)
			)
			(layer "F.Fab")
		)
		(fp_line
			(start 1.1049 -0.724916)
			(end -1.1049 -0.724916)
			(stroke
				(width 0.1)
				(type default)
			)
			(layer "F.Fab")
		)
		(fp_line
			(start -1.1049 0.724916)
			(end 1.1049 0.724916)
			(stroke
				(width 0.1)
				(type default)
			)
			(layer "F.Fab")
		)
		(fp_line
			(start -1.1049 -0.724916)
			(end -1.1049 0.724916)
			(stroke
				(width 0.1)
				(type default)
			)
			(layer "F.Fab")
		)
		(pad "1" smd rect
			(at -0.889 0)
			(size 1.016 1.27)
			(layers "F.Cu" "F.Mask" "F.Paste")
			(net "P3V3_SSD11")
		)
		(pad "2" smd rect
			(at 0.889 0)
			(size 1.016 1.27)
			(layers "F.Cu" "F.Mask" "F.Paste")
			(net "GND")
		)
	)
	(footprint ""
		(layer "F.Cu")
		(at 47.287688 -343.952322 90)
		(property "Reference" "C165"
			(at 0 0 90)
			(layer "F.SilkS")
			(hide yes)
			(effects
				(font
					(size 1.27 1.27)
				)
			)
		)
		(property "Value" ""
			(at 0 0 90)
			(layer "F.Fab")
			(effects
				(font
					(size 1.27 1.27)
				)
			)
		)
		(duplicate_pad_numbers_are_jumpers no)
		(fp_line
			(start 0.299974 -0.150114)
			(end 0.299974 0.150114)
			(stroke
				(width 0.1)
				(type default)
			)
			(layer "F.Fab")
		)
		(fp_line
			(start -0.299974 -0.150114)
			(end 0.299974 -0.150114)
			(stroke
				(width 0.1)
				(type default)
			)
			(layer "F.Fab")
		)
		(fp_line
			(start 0.299974 0.150114)
			(end -0.299974 0.150114)
			(stroke
				(width 0.1)
				(type default)
			)
			(layer "F.Fab")
		)
		(fp_line
			(start -0.299974 0.150114)
			(end -0.299974 -0.150114)
			(stroke
				(width 0.1)
				(type default)
			)
			(layer "F.Fab")
		)
		(pad "1" smd rect
			(at -0.2667 0 90)
			(size 0.3048 0.381)
			(layers "F.Cu" "F.Mask" "F.Paste")
			(net "P5E_PEX0_STN7_TX_DP<125>")
		)
		(pad "2" smd rect
			(at 0.2667 0 90)
			(size 0.3048 0.381)
			(layers "F.Cu" "F.Mask" "F.Paste")
			(net "P5E_PEX0_STN7_TX_C_DP<125>")
		)
	)
	(footprint ""
		(layer "F.Cu")
		(at 394.09624 -47.20082 90)
		(property "Reference" "C337"
			(at 0 0 90)
			(layer "F.SilkS")
			(hide yes)
			(effects
				(font
					(size 1.27 1.27)
				)
			)
		)
		(property "Value" ""
			(at 0 0 90)
			(layer "F.Fab")
			(effects
				(font
					(size 1.27 1.27)
				)
			)
		)
		(duplicate_pad_numbers_are_jumpers no)
		(fp_line
			(start 0.7874 -0.4064)
			(end 0.7874 0.4064)
			(stroke
				(width 0.1524)
				(type default)
			)
			(layer "F.SilkS")
		)
		(fp_line
			(start -0.7874 -0.4064)
			(end 0.7874 -0.4064)
			(stroke
				(width 0.1524)
				(type default)
			)
			(layer "F.SilkS")
		)
		(fp_line
			(start 0.7874 0.4064)
			(end -0.7874 0.4064)
			(stroke
				(width 0.1524)
				(type default)
			)
			(layer "F.SilkS")
		)
		(fp_line
			(start -0.7874 0.4064)
			(end -0.7874 -0.4064)
			(stroke
				(width 0.1524)
				(type default)
			)
			(layer "F.SilkS")
		)
		(fp_line
			(start -0.12065 -0.305054)
			(end -0.12065 -0.2794)
			(stroke
				(width 0.1)
				(type default)
			)
			(layer "F.Fab")
		)
		(fp_line
			(start -0.67945 -0.305054)
			(end -0.12065 -0.305054)
			(stroke
				(width 0.1)
				(type default)
			)
			(layer "F.Fab")
		)
		(fp_line
			(start 0.67945 -0.3048)
			(end 0.67945 0.3048)
			(stroke
				(width 0.1)
				(type default)
			)
			(layer "F.Fab")
		)
		(fp_line
			(start 0.12065 -0.3048)
			(end 0.67945 -0.3048)
			(stroke
				(width 0.1)
				(type default)
			)
			(layer "F.Fab")
		)
		(fp_line
			(start 0.12065 -0.2794)
			(end 0.12065 -0.3048)
			(stroke
				(width 0.1)
				(type default)
			)
			(layer "F.Fab")
		)
		(fp_line
			(start -0.12065 -0.2794)
			(end 0.12065 -0.2794)
			(stroke
				(width 0.1)
				(type default)
			)
			(layer "F.Fab")
		)
		(fp_line
			(start 0.120396 0.2794)
			(end -0.12065 0.2794)
			(stroke
				(width 0.1)
				(type default)
			)
			(layer "F.Fab")
		)
		(fp_line
			(start -0.12065 0.2794)
			(end -0.12065 0.3048)
			(stroke
				(width 0.1)
				(type default)
			)
			(layer "F.Fab")
		)
		(fp_line
			(start 0.67945 0.3048)
			(end 0.120396 0.3048)
			(stroke
				(width 0.1)
				(type default)
			)
			(layer "F.Fab")
		)
		(fp_line
			(start 0.120396 0.3048)
			(end 0.120396 0.2794)
			(stroke
				(width 0.1)
				(type default)
			)
			(layer "F.Fab")
		)
		(fp_line
			(start -0.12065 0.3048)
			(end -0.67945 0.3048)
			(stroke
				(width 0.1)
				(type default)
			)
			(layer "F.Fab")
		)
		(fp_line
			(start -0.67945 0.3048)
			(end -0.67945 -0.305054)
			(stroke
				(width 0.1)
				(type default)
			)
			(layer "F.Fab")
		)
		(pad "1" smd circle
			(at -0.40005 0 90)
			(size 0 0)
			(layers "F.Cu" "F.Mask" "F.Paste")
			(net "P12V_SSD13_R")
		)
		(pad "2" smd circle
			(at 0.40005 0 90)
			(size 0 0)
			(layers "F.Cu" "F.Mask" "F.Paste")
			(net "GND")
		)
	)
	(footprint ""
		(layer "F.Cu")
		(at 115.339368 -265.949938 180)
		(property "Reference" "PR7132"
			(at 0 0 180)
			(layer "F.SilkS")
			(hide yes)
			(effects
				(font
					(size 1.27 1.27)
				)
			)
		)
		(property "Value" ""
			(at 0 0 180)
			(layer "F.Fab")
			(effects
				(font
					(size 1.27 1.27)
				)
			)
		)
		(duplicate_pad_numbers_are_jumpers no)
		(fp_line
			(start 0.7874 0.4064)
			(end -0.7874 0.4064)
			(stroke
				(width 0.1524)
				(type default)
			)
			(layer "F.SilkS")
		)
		(fp_line
			(start 0.7874 -0.4064)
			(end 0.7874 0.4064)
			(stroke
				(width 0.1524)
				(type default)
			)
			(layer "F.SilkS")
		)
		(fp_line
			(start -0.7874 0.4064)
			(end -0.7874 -0.4064)
			(stroke
				(width 0.1524)
				(type default)
			)
			(layer "F.SilkS")
		)
		(fp_line
			(start -0.7874 -0.4064)
			(end 0.7874 -0.4064)
			(stroke
				(width 0.1524)
				(type default)
			)
			(layer "F.SilkS")
		)
		(fp_line
			(start 0.67945 0.3048)
			(end 0.120396 0.3048)
			(stroke
				(width 0.1)
				(type default)
			)
			(layer "F.Fab")
		)
		(fp_line
			(start 0.67945 -0.3048)
			(end 0.67945 0.3048)
			(stroke
				(width 0.1)
				(type default)
			)
			(layer "F.Fab")
		)
		(fp_line
			(start 0.12065 -0.2794)
			(end 0.12065 -0.3048)
			(stroke
				(width 0.1)
				(type default)
			)
			(layer "F.Fab")
		)
		(fp_line
			(start 0.12065 -0.3048)
			(end 0.67945 -0.3048)
			(stroke
				(width 0.1)
				(type default)
			)
			(layer "F.Fab")
		)
		(fp_line
			(start 0.120396 0.3048)
			(end 0.120396 0.2794)
			(stroke
				(width 0.1)
				(type default)
			)
			(layer "F.Fab")
		)
		(fp_line
			(start 0.120396 0.2794)
			(end -0.12065 0.2794)
			(stroke
				(width 0.1)
				(type default)
			)
			(layer "F.Fab")
		)
		(fp_line
			(start -0.12065 0.3048)
			(end -0.67945 0.3048)
			(stroke
				(width 0.1)
				(type default)
			)
			(layer "F.Fab")
		)
		(fp_line
			(start -0.12065 0.2794)
			(end -0.12065 0.3048)
			(stroke
				(width 0.1)
				(type default)
			)
			(layer "F.Fab")
		)
		(fp_line
			(start -0.12065 -0.2794)
			(end 0.12065 -0.2794)
			(stroke
				(width 0.1)
				(type default)
			)
			(layer "F.Fab")
		)
		(fp_line
			(start -0.12065 -0.305054)
			(end -0.12065 -0.2794)
			(stroke
				(width 0.1)
				(type default)
			)
			(layer "F.Fab")
		)
		(fp_line
			(start -0.67945 0.3048)
			(end -0.67945 -0.305054)
			(stroke
				(width 0.1)
				(type default)
			)
			(layer "F.Fab")
		)
		(fp_line
			(start -0.67945 -0.305054)
			(end -0.12065 -0.305054)
			(stroke
				(width 0.1)
				(type default)
			)
			(layer "F.Fab")
		)
		(pad "1" smd circle
			(at -0.40005 0 180)
			(size 0 0)
			(layers "F.Cu" "F.Mask" "F.Paste")
			(net "NC_P0V8_PEX0_ISEN5")
		)
		(pad "2" smd circle
			(at 0.40005 0 180)
			(size 0 0)
			(layers "F.Cu" "F.Mask" "F.Paste")
			(net "GND")
		)
	)
	(footprint ""
		(layer "F.Cu")
		(at 188.534548 -33.631886 180)
		(property "Reference" "C293"
			(at 0 0 180)
			(layer "F.SilkS")
			(hide yes)
			(effects
				(font
					(size 1.27 1.27)
				)
			)
		)
		(property "Value" ""
			(at 0 0 180)
			(layer "F.Fab")
			(effects
				(font
					(size 1.27 1.27)
				)
			)
		)
		(duplicate_pad_numbers_are_jumpers no)
		(fp_line
			(start 0.299974 0.150114)
			(end -0.299974 0.150114)
			(stroke
				(width 0.1)
				(type default)
			)
			(layer "F.Fab")
		)
		(fp_line
			(start 0.299974 -0.150114)
			(end 0.299974 0.150114)
			(stroke
				(width 0.1)
				(type default)
			)
			(layer "F.Fab")
		)
		(fp_line
			(start -0.299974 0.150114)
			(end -0.299974 -0.150114)
			(stroke
				(width 0.1)
				(type default)
			)
			(layer "F.Fab")
		)
		(fp_line
			(start -0.299974 -0.150114)
			(end 0.299974 -0.150114)
			(stroke
				(width 0.1)
				(type default)
			)
			(layer "F.Fab")
		)
		(pad "1" smd rect
			(at -0.2667 0 180)
			(size 0.3048 0.381)
			(layers "F.Cu" "F.Mask" "F.Paste")
			(net "P5E_PEX1_STN2_TX_DN<39>")
		)
		(pad "2" smd rect
			(at 0.2667 0 180)
			(size 0.3048 0.381)
			(layers "F.Cu" "F.Mask" "F.Paste")
			(net "P5E_PEX1_STN2_TX_C_DN<39>")
		)
	)
)
